# T6G (Grand Teton) — schematic netlist excerpt (pin names and nets, part order shuffled) for the footprints in the layout excerpt that follows; sources: Cadence DE-HDL packaged netlist, KiCad conversion of 04192023_DAF0TMB3IC0_F0TG_MB_C_brd_V02_OCP.brd

C1043  Q_CAP  0.1UF 10V 10% X7S  pkg C0201  page 312 : A = P0V9_CPU0_RT3_2A ; B = GND
R3525  Q_RES  54.9K 1% CHIP  pkg 0402LF  page 126 : A = P3V3_AUX ; B = GPU_FPGA_EROT_FATALERR_N
C346  Q_CAP  1UF 4V 20% X6S  pkg 0201  page 334 : A = P0V9_CPU1_RT1_2A ; B = GND

(kicad_pcb
	(version 20260206)
	(generator "pcbnew")
	(generator_version "10.0")
	(general
		(thickness 1.6)
		(legacy_teardrops no)
	)
	(paper "A4")
	(title_block
		(title "04192023_DAF0TMB3IC0_F0TG_MB_C_brd_V02_OCP.brd")
		(comment 1 "Grand Teton / footprints 8022-8024 of 8354")
	)
	(layers
		(0 "F.Cu" signal "TOP")
		(4 "In1.Cu" signal "GND")
		(6 "In2.Cu" signal "IN1")
		(8 "In3.Cu" signal "GND1")
		(10 "In4.Cu" signal "IN2")
		(12 "In5.Cu" signal "GND2")
		(14 "In6.Cu" signal "IN3")
		(16 "In7.Cu" signal "GND3")
		(18 "In8.Cu" signal "VCC")
		(20 "In9.Cu" signal "VCC1")
		(22 "In10.Cu" signal "GND4")
		(24 "In11.Cu" signal "IN4")
		(26 "In12.Cu" signal "GND5")
		(28 "In13.Cu" signal "IN5")
		(30 "In14.Cu" signal "GND6")
		(32 "In15.Cu" signal "IN6")
		(34 "In16.Cu" signal "GND7")
		(2 "B.Cu" signal "BOTTOM")
		(9 "F.Adhes" user "F.Adhesive")
		(11 "B.Adhes" user "B.Adhesive")
		(13 "F.Paste" user "Package Geometry/Pastemask Top")
		(15 "B.Paste" user "Package Geometry/Pastemask Bottom")
		(5 "F.SilkS" user "Ref Des/Silkscreen Top")
		(7 "B.SilkS" user "Ref Des/Silkscreen Bottom")
		(1 "F.Mask" user "Board Geometry/Soldermask Top")
		(3 "B.Mask" user "Board Geometry/Soldermask Bottom")
		(17 "Dwgs.User" user "User.Drawings")
		(19 "Cmts.User" user "User.Comments")
		(21 "Eco1.User" user "User.Eco1")
		(23 "Eco2.User" user "User.Eco2")
		(25 "Edge.Cuts" user "Board Geometry/Outline")
		(27 "Margin" user)
		(31 "F.CrtYd" user "Package Geometry/Place Bound Top")
		(29 "B.CrtYd" user "Package Geometry/Place Bound Bottom")
		(35 "F.Fab" user "Ref Des/Assembly Top")
		(33 "B.Fab" user "Ref Des/Assembly Bottom")
	)
	(footprint ""
		(layer "B.Cu")
		(at 388.618476 -396.393162 -90)
		(property "Reference" "C1043"
			(at 0 0 90)
			(layer "B.SilkS")
			(hide yes)
			(effects
				(font
					(size 1.27 1.27)
				)
				(justify mirror)
			)
		)
		(property "Value" ""
			(at 0 0 90)
			(layer "B.Fab")
			(effects
				(font
					(size 1.27 1.27)
				)
				(justify mirror)
			)
		)
		(duplicate_pad_numbers_are_jumpers no)
		(fp_line
			(start -0.299974 0.150114)
			(end 0.299974 0.150114)
			(stroke
				(width 0.1)
				(type default)
			)
			(layer "B.Fab")
		)
		(fp_line
			(start 0.299974 0.150114)
			(end 0.299974 -0.150114)
			(stroke
				(width 0.1)
				(type default)
			)
			(layer "B.Fab")
		)
		(fp_line
			(start -0.299974 -0.150114)
			(end -0.299974 0.150114)
			(stroke
				(width 0.1)
				(type default)
			)
			(layer "B.Fab")
		)
		(fp_line
			(start 0.299974 -0.150114)
			(end -0.299974 -0.150114)
			(stroke
				(width 0.1)
				(type default)
			)
			(layer "B.Fab")
		)
		(pad "1" smd rect
			(at 0.2667 0 90)
			(size 0.3048 0.381)
			(layers "B.Cu" "B.Mask" "B.Paste")
			(net "P0V9_CPU0_RT3_2A")
		)
		(pad "2" smd rect
			(at -0.2667 0 90)
			(size 0.3048 0.381)
			(layers "B.Cu" "B.Mask" "B.Paste")
			(net "GND")
		)
	)
	(footprint ""
		(layer "B.Cu")
		(at 116.078 -417.957 90)
		(property "Reference" "R3525"
			(at 0 0 90)
			(layer "B.SilkS")
			(hide yes)
			(effects
				(font
					(size 1.27 1.27)
				)
				(justify mirror)
			)
		)
		(property "Value" ""
			(at 0 0 90)
			(layer "B.Fab")
			(effects
				(font
					(size 1.27 1.27)
				)
				(justify mirror)
			)
		)
		(duplicate_pad_numbers_are_jumpers no)
		(fp_line
			(start 0.7874 -0.4064)
			(end -0.7874 -0.4064)
			(stroke
				(width 0.1524)
				(type default)
			)
			(layer "B.SilkS")
		)
		(fp_line
			(start -0.7874 -0.4064)
			(end -0.7874 0.4064)
			(stroke
				(width 0.1524)
				(type default)
			)
			(layer "B.SilkS")
		)
		(fp_line
			(start 0.7874 0.4064)
			(end 0.7874 -0.4064)
			(stroke
				(width 0.1524)
				(type default)
			)
			(layer "B.SilkS")
		)
		(fp_line
			(start -0.7874 0.4064)
			(end 0.7874 0.4064)
			(stroke
				(width 0.1524)
				(type default)
			)
			(layer "B.SilkS")
		)
		(fp_line
			(start 0.67945 -0.305054)
			(end 0.12065 -0.305054)
			(stroke
				(width 0.1)
				(type default)
			)
			(layer "B.Fab")
		)
		(fp_line
			(start 0.12065 -0.305054)
			(end 0.12065 -0.2794)
			(stroke
				(width 0.1)
				(type default)
			)
			(layer "B.Fab")
		)
		(fp_line
			(start -0.12065 -0.3048)
			(end -0.67945 -0.3048)
			(stroke
				(width 0.1)
				(type default)
			)
			(layer "B.Fab")
		)
		(fp_line
			(start -0.67945 -0.3048)
			(end -0.67945 0.3048)
			(stroke
				(width 0.1)
				(type default)
			)
			(layer "B.Fab")
		)
		(fp_line
			(start 0.12065 -0.2794)
			(end -0.12065 -0.2794)
			(stroke
				(width 0.1)
				(type default)
			)
			(layer "B.Fab")
		)
		(fp_line
			(start -0.12065 -0.2794)
			(end -0.12065 -0.3048)
			(stroke
				(width 0.1)
				(type default)
			)
			(layer "B.Fab")
		)
		(fp_line
			(start 0.12065 0.2794)
			(end 0.12065 0.3048)
			(stroke
				(width 0.1)
				(type default)
			)
			(layer "B.Fab")
		)
		(fp_line
			(start -0.120396 0.2794)
			(end 0.12065 0.2794)
			(stroke
				(width 0.1)
				(type default)
			)
			(layer "B.Fab")
		)
		(fp_line
			(start 0.67945 0.3048)
			(end 0.67945 -0.305054)
			(stroke
				(width 0.1)
				(type default)
			)
			(layer "B.Fab")
		)
		(fp_line
			(start 0.12065 0.3048)
			(end 0.67945 0.3048)
			(stroke
				(width 0.1)
				(type default)
			)
			(layer "B.Fab")
		)
		(fp_line
			(start -0.120396 0.3048)
			(end -0.120396 0.2794)
			(stroke
				(width 0.1)
				(type default)
			)
			(layer "B.Fab")
		)
		(fp_line
			(start -0.67945 0.3048)
			(end -0.120396 0.3048)
			(stroke
				(width 0.1)
				(type default)
			)
			(layer "B.Fab")
		)
		(pad "1" smd circle
			(at 0.40005 0 270)
			(size 0 0)
			(layers "B.Cu" "B.Mask" "B.Paste")
			(net "P3V3_AUX")
		)
		(pad "2" smd circle
			(at -0.40005 0 270)
			(size 0 0)
			(layers "B.Cu" "B.Mask" "B.Paste")
			(net "GPU_FPGA_EROT_FATALERR_N")
		)
	)
	(footprint ""
		(layer "B.Cu")
		(at 96.706436 -386.766562 90)
		(property "Reference" "C346"
			(at 0 0 90)
			(layer "B.SilkS")
			(hide yes)
			(effects
				(font
					(size 1.27 1.27)
				)
				(justify mirror)
			)
		)
		(property "Value" ""
			(at 0 0 90)
			(layer "B.Fab")
			(effects
				(font
					(size 1.27 1.27)
				)
				(justify mirror)
			)
		)
		(duplicate_pad_numbers_are_jumpers no)
		(fp_line
			(start 0.299974 -0.150114)
			(end -0.299974 -0.150114)
			(stroke
				(width 0.1)
				(type default)
			)
			(layer "B.Fab")
		)
		(fp_line
			(start -0.299974 -0.150114)
			(end -0.299974 0.150114)
			(stroke
				(width 0.1)
				(type default)
			)
			(layer "B.Fab")
		)
		(fp_line
			(start 0.299974 0.150114)
			(end 0.299974 -0.150114)
			(stroke
				(width 0.1)
				(type default)
			)
			(layer "B.Fab")
		)
		(fp_line
			(start -0.299974 0.150114)
			(end 0.299974 0.150114)
			(stroke
				(width 0.1)
				(type default)
			)
			(layer "B.Fab")
		)
		(pad "1" smd rect
			(at 0.2667 0 270)
			(size 0.3048 0.381)
			(layers "B.Cu" "B.Mask" "B.Paste")
			(net "P0V9_CPU1_RT1_2A")
		)
		(pad "2" smd rect
			(at -0.2667 0 270)
			(size 0.3048 0.381)
			(layers "B.Cu" "B.Mask" "B.Paste")
			(net "GND")
		)
	)
)
